(kicad_pcb
	(version 20260206)
	(generator "pcbnew")
	(generator_version "10.0")
	(general
		(thickness 1.6)
		(legacy_teardrops no)
	)
	(paper "A4")
	(title_block
		(title "01162023_DA0F0TEBIF0_F0T_Expander_BD_F_brd_V02_OCP.brd")
		(comment 1 "Grand Teton / footprints 1536-1541 of 9728")
	)
	(layers
		(0 "F.Cu" signal "TOP")
		(4 "In1.Cu" signal "GND")
		(6 "In2.Cu" signal "VCC")
		(8 "In3.Cu" signal "VCC1")
		(10 "In4.Cu" signal "GND1")
		(12 "In5.Cu" signal "IN1")
		(14 "In6.Cu" signal "GND2")
		(16 "In7.Cu" signal "IN2")
		(18 "In8.Cu" signal "GND3")
		(20 "In9.Cu" signal "IN3")
		(22 "In10.Cu" signal "GND4")
		(24 "In11.Cu" signal "IN4")
		(26 "In12.Cu" signal "GND5")
		(28 "In13.Cu" signal "IN5")
		(30 "In14.Cu" signal "GND6")
		(32 "In15.Cu" signal "IN6")
		(34 "In16.Cu" signal "GND7")
		(2 "B.Cu" signal "BOTTOM")
		(9 "F.Adhes" user "F.Adhesive")
		(11 "B.Adhes" user "B.Adhesive")
		(13 "F.Paste" user "Package Geometry/Pastemask Top")
		(15 "B.Paste" user "Package Geometry/Pastemask Bottom")
		(5 "F.SilkS" user "Ref Des/Silkscreen Top")
		(7 "B.SilkS" user "Ref Des/Silkscreen Bottom")
		(1 "F.Mask" user "Board Geometry/Soldermask Top")
		(3 "B.Mask" user "Board Geometry/Soldermask Bottom")
		(17 "Dwgs.User" user "User.Drawings")
		(19 "Cmts.User" user "User.Comments")
		(21 "Eco1.User" user "User.Eco1")
		(23 "Eco2.User" user "User.Eco2")
		(25 "Edge.Cuts" user "Board Geometry/Outline")
		(27 "Margin" user)
		(31 "F.CrtYd" user "Package Geometry/Place Bound Top")
		(29 "B.CrtYd" user "Package Geometry/Place Bound Bottom")
		(35 "F.Fab" user "Ref Des/Assembly Top")
		(33 "B.Fab" user "Ref Des/Assembly Bottom")
	)
	(footprint ""
		(layer "F.Cu")
		(at 454.523602 -245.0465 -90)
		(property "Reference" "C4429"
			(at 0 0 270)
			(layer "F.SilkS")
			(hide yes)
			(effects
				(font
					(size 1.27 1.27)
				)
			)
		)
		(property "Value" ""
			(at 0 0 270)
			(layer "F.Fab")
			(effects
				(font
					(size 1.27 1.27)
				)
			)
		)
		(duplicate_pad_numbers_are_jumpers no)
		(fp_line
			(start -0.7874 0.4064)
			(end -0.7874 -0.4064)
			(stroke
				(width 0.1524)
				(type default)
			)
			(layer "F.SilkS")
		)
		(fp_line
			(start 0.7874 0.4064)
			(end -0.7874 0.4064)
			(stroke
				(width 0.1524)
				(type default)
			)
			(layer "F.SilkS")
		)
		(fp_line
			(start -0.7874 -0.4064)
			(end 0.7874 -0.4064)
			(stroke
				(width 0.1524)
				(type default)
			)
			(layer "F.SilkS")
		)
		(fp_line
			(start 0.7874 -0.4064)
			(end 0.7874 0.4064)
			(stroke
				(width 0.1524)
				(type default)
			)
			(layer "F.SilkS")
		)
		(fp_line
			(start -0.67945 0.3048)
			(end -0.67945 -0.305054)
			(stroke
				(width 0.1)
				(type default)
			)
			(layer "F.Fab")
		)
		(fp_line
			(start -0.12065 0.3048)
			(end -0.67945 0.3048)
			(stroke
				(width 0.1)
				(type default)
			)
			(layer "F.Fab")
		)
		(fp_line
			(start 0.120396 0.3048)
			(end 0.120396 0.2794)
			(stroke
				(width 0.1)
				(type default)
			)
			(layer "F.Fab")
		)
		(fp_line
			(start 0.67945 0.3048)
			(end 0.120396 0.3048)
			(stroke
				(width 0.1)
				(type default)
			)
			(layer "F.Fab")
		)
		(fp_line
			(start -0.12065 0.2794)
			(end -0.12065 0.3048)
			(stroke
				(width 0.1)
				(type default)
			)
			(layer "F.Fab")
		)
		(fp_line
			(start 0.120396 0.2794)
			(end -0.12065 0.2794)
			(stroke
				(width 0.1)
				(type default)
			)
			(layer "F.Fab")
		)
		(fp_line
			(start -0.12065 -0.2794)
			(end 0.12065 -0.2794)
			(stroke
				(width 0.1)
				(type default)
			)
			(layer "F.Fab")
		)
		(fp_line
			(start 0.12065 -0.2794)
			(end 0.12065 -0.3048)
			(stroke
				(width 0.1)
				(type default)
			)
			(layer "F.Fab")
		)
		(fp_line
			(start 0.12065 -0.3048)
			(end 0.67945 -0.3048)
			(stroke
				(width 0.1)
				(type default)
			)
			(layer "F.Fab")
		)
		(fp_line
			(start 0.67945 -0.3048)
			(end 0.67945 0.3048)
			(stroke
				(width 0.1)
				(type default)
			)
			(layer "F.Fab")
		)
		(fp_line
			(start -0.67945 -0.305054)
			(end -0.12065 -0.305054)
			(stroke
				(width 0.1)
				(type default)
			)
			(layer "F.Fab")
		)
		(fp_line
			(start -0.12065 -0.305054)
			(end -0.12065 -0.2794)
			(stroke
				(width 0.1)
				(type default)
			)
			(layer "F.Fab")
		)
		(pad "1" smd circle
			(at -0.40005 0 270)
			(size 0 0)
			(layers "F.Cu" "F.Mask" "F.Paste")
			(net "P5V_AUX")
		)
		(pad "2" smd circle
			(at 0.40005 0 270)
			(size 0 0)
			(layers "F.Cu" "F.Mask" "F.Paste")
			(net "GND")
		)
	)
	(footprint ""
		(layer "F.Cu")
		(at 89.478866 -308.323488 135)
		(property "Reference" "R1254"
			(at 0 0 135)
			(layer "F.SilkS")
			(hide yes)
			(effects
				(font
					(size 1.27 1.27)
				)
			)
		)
		(property "Value" ""
			(at 0 0 135)
			(layer "F.Fab")
			(effects
				(font
					(size 1.27 1.27)
				)
			)
		)
		(duplicate_pad_numbers_are_jumpers no)
		(fp_line
			(start 0.787389 -0.406267)
			(end 0.787389 0.406267)
			(stroke
				(width 0.1524)
				(type default)
			)
			(layer "F.SilkS")
		)
		(fp_line
			(start 0.787389 0.406267)
			(end -0.787389 0.406267)
			(stroke
				(width 0.1524)
				(type default)
			)
			(layer "F.SilkS")
		)
		(fp_line
			(start -0.787389 -0.406267)
			(end 0.787389 -0.406267)
			(stroke
				(width 0.1524)
				(type default)
			)
			(layer "F.SilkS")
		)
		(fp_line
			(start -0.787389 0.406267)
			(end -0.787389 -0.406267)
			(stroke
				(width 0.1524)
				(type default)
			)
			(layer "F.SilkS")
		)
		(fp_line
			(start 0.679446 -0.30479)
			(end 0.679446 0.30479)
			(stroke
				(width 0.1)
				(type default)
			)
			(layer "F.Fab")
		)
		(fp_line
			(start 0.120515 -0.30479)
			(end 0.679446 -0.30479)
			(stroke
				(width 0.1)
				(type default)
			)
			(layer "F.Fab")
		)
		(fp_line
			(start 0.120695 -0.279466)
			(end 0.120515 -0.30479)
			(stroke
				(width 0.1)
				(type default)
			)
			(layer "F.Fab")
		)
		(fp_line
			(start 0.679446 0.30479)
			(end 0.120515 0.30479)
			(stroke
				(width 0.1)
				(type default)
			)
			(layer "F.Fab")
		)
		(fp_line
			(start -0.120695 -0.304969)
			(end -0.120695 -0.279466)
			(stroke
				(width 0.1)
				(type default)
			)
			(layer "F.Fab")
		)
		(fp_line
			(start -0.120695 -0.279466)
			(end 0.120695 -0.279466)
			(stroke
				(width 0.1)
				(type default)
			)
			(layer "F.Fab")
		)
		(fp_line
			(start 0.120335 0.279466)
			(end -0.120695 0.279466)
			(stroke
				(width 0.1)
				(type default)
			)
			(layer "F.Fab")
		)
		(fp_line
			(start 0.120515 0.30479)
			(end 0.120335 0.279466)
			(stroke
				(width 0.1)
				(type default)
			)
			(layer "F.Fab")
		)
		(fp_line
			(start -0.679446 -0.305149)
			(end -0.120695 -0.304969)
			(stroke
				(width 0.1)
				(type default)
			)
			(layer "F.Fab")
		)
		(fp_line
			(start -0.120695 0.279466)
			(end -0.120515 0.30479)
			(stroke
				(width 0.1)
				(type default)
			)
			(layer "F.Fab")
		)
		(fp_line
			(start -0.120515 0.30479)
			(end -0.679446 0.30479)
			(stroke
				(width 0.1)
				(type default)
			)
			(layer "F.Fab")
		)
		(fp_line
			(start -0.679446 0.30479)
			(end -0.679446 -0.305149)
			(stroke
				(width 0.1)
				(type default)
			)
			(layer "F.Fab")
		)
		(pad "1" smd circle
			(at -0.40005 0 135)
			(size 0 0)
			(layers "F.Cu" "F.Mask" "F.Paste")
			(net "GND")
		)
		(pad "2" smd circle
			(at 0.40005 0 135)
			(size 0 0)
			(layers "F.Cu" "F.Mask" "F.Paste")
			(net "PEX0_SPARE7")
		)
	)
	(footprint ""
		(layer "F.Cu")
		(at 428.83963 -137.645648)
		(property "Reference" "R363"
			(at 0 0 0)
			(layer "F.SilkS")
			(hide yes)
			(effects
				(font
					(size 1.27 1.27)
				)
			)
		)
		(property "Value" ""
			(at 0 0 0)
			(layer "F.Fab")
			(effects
				(font
					(size 1.27 1.27)
				)
			)
		)
		(duplicate_pad_numbers_are_jumpers no)
		(fp_line
			(start -0.7874 -0.4064)
			(end 0.7874 -0.4064)
			(stroke
				(width 0.1524)
				(type default)
			)
			(layer "F.SilkS")
		)
		(fp_line
			(start -0.7874 0.4064)
			(end -0.7874 -0.4064)
			(stroke
				(width 0.1524)
				(type default)
			)
			(layer "F.SilkS")
		)
		(fp_line
			(start 0.7874 -0.4064)
			(end 0.7874 0.4064)
			(stroke
				(width 0.1524)
				(type default)
			)
			(layer "F.SilkS")
		)
		(fp_line
			(start 0.7874 0.4064)
			(end -0.7874 0.4064)
			(stroke
				(width 0.1524)
				(type default)
			)
			(layer "F.SilkS")
		)
		(fp_line
			(start -0.67945 -0.305054)
			(end -0.12065 -0.305054)
			(stroke
				(width 0.1)
				(type default)
			)
			(layer "F.Fab")
		)
		(fp_line
			(start -0.67945 0.3048)
			(end -0.67945 -0.305054)
			(stroke
				(width 0.1)
				(type default)
			)
			(layer "F.Fab")
		)
		(fp_line
			(start -0.12065 -0.305054)
			(end -0.12065 -0.2794)
			(stroke
				(width 0.1)
				(type default)
			)
			(layer "F.Fab")
		)
		(fp_line
			(start -0.12065 -0.2794)
			(end 0.12065 -0.2794)
			(stroke
				(width 0.1)
				(type default)
			)
			(layer "F.Fab")
		)
		(fp_line
			(start -0.12065 0.2794)
			(end -0.12065 0.3048)
			(stroke
				(width 0.1)
				(type default)
			)
			(layer "F.Fab")
		)
		(fp_line
			(start -0.12065 0.3048)
			(end -0.67945 0.3048)
			(stroke
				(width 0.1)
				(type default)
			)
			(layer "F.Fab")
		)
		(fp_line
			(start 0.120396 0.2794)
			(end -0.12065 0.2794)
			(stroke
				(width 0.1)
				(type default)
			)
			(layer "F.Fab")
		)
		(fp_line
			(start 0.120396 0.3048)
			(end 0.120396 0.2794)
			(stroke
				(width 0.1)
				(type default)
			)
			(layer "F.Fab")
		)
		(fp_line
			(start 0.12065 -0.3048)
			(end 0.67945 -0.3048)
			(stroke
				(width 0.1)
				(type default)
			)
			(layer "F.Fab")
		)
		(fp_line
			(start 0.12065 -0.2794)
			(end 0.12065 -0.3048)
			(stroke
				(width 0.1)
				(type default)
			)
			(layer "F.Fab")
		)
		(fp_line
			(start 0.67945 -0.3048)
			(end 0.67945 0.3048)
			(stroke
				(width 0.1)
				(type default)
			)
			(layer "F.Fab")
		)
		(fp_line
			(start 0.67945 0.3048)
			(end 0.120396 0.3048)
			(stroke
				(width 0.1)
				(type default)
			)
			(layer "F.Fab")
		)
		(pad "1" smd circle
			(at -0.40005 0)
			(size 0 0)
			(layers "F.Cu" "F.Mask" "F.Paste")
			(net "PRSNTB0_NIC7_N")
		)
		(pad "2" smd circle
			(at 0.40005 0)
			(size 0 0)
			(layers "F.Cu" "F.Mask" "F.Paste")
			(net "P3V3_AUX")
		)
	)
	(footprint ""
		(layer "F.Cu")
		(at 350.647 -173.482 90)
		(property "Reference" "C3602"
			(at 0 0 90)
			(layer "F.SilkS")
			(hide yes)
			(effects
				(font
					(size 1.27 1.27)
				)
			)
		)
		(property "Value" ""
			(at 0 0 90)
			(layer "F.Fab")
			(effects
				(font
					(size 1.27 1.27)
				)
			)
		)
		(duplicate_pad_numbers_are_jumpers no)
		(fp_line
			(start 0.7874 -0.4064)
			(end 0.7874 0.4064)
			(stroke
				(width 0.1524)
				(type default)
			)
			(layer "F.SilkS")
		)
		(fp_line
			(start -0.7874 -0.4064)
			(end 0.7874 -0.4064)
			(stroke
				(width 0.1524)
				(type default)
			)
			(layer "F.SilkS")
		)
		(fp_line
			(start 0.7874 0.4064)
			(end -0.7874 0.4064)
			(stroke
				(width 0.1524)
				(type default)
			)
			(layer "F.SilkS")
		)
		(fp_line
			(start -0.7874 0.4064)
			(end -0.7874 -0.4064)
			(stroke
				(width 0.1524)
				(type default)
			)
			(layer "F.SilkS")
		)
		(fp_line
			(start -0.12065 -0.305054)
			(end -0.12065 -0.2794)
			(stroke
				(width 0.1)
				(type default)
			)
			(layer "F.Fab")
		)
		(fp_line
			(start -0.67945 -0.305054)
			(end -0.12065 -0.305054)
			(stroke
				(width 0.1)
				(type default)
			)
			(layer "F.Fab")
		)
		(fp_line
			(start 0.67945 -0.3048)
			(end 0.67945 0.3048)
			(stroke
				(width 0.1)
				(type default)
			)
			(layer "F.Fab")
		)
		(fp_line
			(start 0.12065 -0.3048)
			(end 0.67945 -0.3048)
			(stroke
				(width 0.1)
				(type default)
			)
			(layer "F.Fab")
		)
		(fp_line
			(start 0.12065 -0.2794)
			(end 0.12065 -0.3048)
			(stroke
				(width 0.1)
				(type default)
			)
			(layer "F.Fab")
		)
		(fp_line
			(start -0.12065 -0.2794)
			(end 0.12065 -0.2794)
			(stroke
				(width 0.1)
				(type default)
			)
			(layer "F.Fab")
		)
		(fp_line
			(start 0.120396 0.2794)
			(end -0.12065 0.2794)
			(stroke
				(width 0.1)
				(type default)
			)
			(layer "F.Fab")
		)
		(fp_line
			(start -0.12065 0.2794)
			(end -0.12065 0.3048)
			(stroke
				(width 0.1)
				(type default)
			)
			(layer "F.Fab")
		)
		(fp_line
			(start 0.67945 0.3048)
			(end 0.120396 0.3048)
			(stroke
				(width 0.1)
				(type default)
			)
			(layer "F.Fab")
		)
		(fp_line
			(start 0.120396 0.3048)
			(end 0.120396 0.2794)
			(stroke
				(width 0.1)
				(type default)
			)
			(layer "F.Fab")
		)
		(fp_line
			(start -0.12065 0.3048)
			(end -0.67945 0.3048)
			(stroke
				(width 0.1)
				(type default)
			)
			(layer "F.Fab")
		)
		(fp_line
			(start -0.67945 0.3048)
			(end -0.67945 -0.305054)
			(stroke
				(width 0.1)
				(type default)
			)
			(layer "F.Fab")
		)
		(pad "1" smd circle
			(at -0.40005 0 90)
			(size 0 0)
			(layers "F.Cu" "F.Mask" "F.Paste")
			(net "P3V3_AUX")
		)
		(pad "2" smd circle
			(at 0.40005 0 90)
			(size 0 0)
			(layers "F.Cu" "F.Mask" "F.Paste")
			(net "GND")
		)
	)
	(footprint ""
		(layer "F.Cu")
		(at 450.230494 -118.76024)
		(property "Reference" "R6045"
			(at 0 0 0)
			(layer "F.SilkS")
			(hide yes)
			(effects
				(font
					(size 1.27 1.27)
				)
			)
		)
		(property "Value" ""
			(at 0 0 0)
			(layer "F.Fab")
			(effects
				(font
					(size 1.27 1.27)
				)
			)
		)
		(duplicate_pad_numbers_are_jumpers no)
		(fp_line
			(start -0.7874 -0.4064)
			(end 0.7874 -0.4064)
			(stroke
				(width 0.1524)
				(type default)
			)
			(layer "F.SilkS")
		)
		(fp_line
			(start -0.7874 0.4064)
			(end -0.7874 -0.4064)
			(stroke
				(width 0.1524)
				(type default)
			)
			(layer "F.SilkS")
		)
		(fp_line
			(start 0.7874 -0.4064)
			(end 0.7874 0.4064)
			(stroke
				(width 0.1524)
				(type default)
			)
			(layer "F.SilkS")
		)
		(fp_line
			(start 0.7874 0.4064)
			(end -0.7874 0.4064)
			(stroke
				(width 0.1524)
				(type default)
			)
			(layer "F.SilkS")
		)
		(fp_line
			(start -0.67945 -0.305054)
			(end -0.12065 -0.305054)
			(stroke
				(width 0.1)
				(type default)
			)
			(layer "F.Fab")
		)
		(fp_line
			(start -0.67945 0.3048)
			(end -0.67945 -0.305054)
			(stroke
				(width 0.1)
				(type default)
			)
			(layer "F.Fab")
		)
		(fp_line
			(start -0.12065 -0.305054)
			(end -0.12065 -0.2794)
			(stroke
				(width 0.1)
				(type default)
			)
			(layer "F.Fab")
		)
		(fp_line
			(start -0.12065 -0.2794)
			(end 0.12065 -0.2794)
			(stroke
				(width 0.1)
				(type default)
			)
			(layer "F.Fab")
		)
		(fp_line
			(start -0.12065 0.2794)
			(end -0.12065 0.3048)
			(stroke
				(width 0.1)
				(type default)
			)
			(layer "F.Fab")
		)
		(fp_line
			(start -0.12065 0.3048)
			(end -0.67945 0.3048)
			(stroke
				(width 0.1)
				(type default)
			)
			(layer "F.Fab")
		)
		(fp_line
			(start 0.120396 0.2794)
			(end -0.12065 0.2794)
			(stroke
				(width 0.1)
				(type default)
			)
			(layer "F.Fab")
		)
		(fp_line
			(start 0.120396 0.3048)
			(end 0.120396 0.2794)
			(stroke
				(width 0.1)
				(type default)
			)
			(layer "F.Fab")
		)
		(fp_line
			(start 0.12065 -0.3048)
			(end 0.67945 -0.3048)
			(stroke
				(width 0.1)
				(type default)
			)
			(layer "F.Fab")
		)
		(fp_line
			(start 0.12065 -0.2794)
			(end 0.12065 -0.3048)
			(stroke
				(width 0.1)
				(type default)
			)
			(layer "F.Fab")
		)
		(fp_line
			(start 0.67945 -0.3048)
			(end 0.67945 0.3048)
			(stroke
				(width 0.1)
				(type default)
			)
			(layer "F.Fab")
		)
		(fp_line
			(start 0.67945 0.3048)
			(end 0.120396 0.3048)
			(stroke
				(width 0.1)
				(type default)
			)
			(layer "F.Fab")
		)
		(pad "1" smd circle
			(at -0.40005 0)
			(size 0 0)
			(layers "F.Cu" "F.Mask" "F.Paste")
			(net "P3V3_AUX")
		)
		(pad "2" smd circle
			(at 0.40005 0)
			(size 0 0)
			(layers "F.Cu" "F.Mask" "F.Paste")
			(net "PWRGD_P3V3_NIC7_D")
		)
	)
	(footprint ""
		(layer "F.Cu")
		(at 446.57391 -72.766682 90)
		(property "Reference" "PR7095"
			(at 0 0 90)
			(layer "F.SilkS")
			(hide yes)
			(effects
				(font
					(size 1.27 1.27)
				)
			)
		)
		(property "Value" ""
			(at 0 0 90)
			(layer "F.Fab")
			(effects
				(font
					(size 1.27 1.27)
				)
			)
		)
		(duplicate_pad_numbers_are_jumpers no)
		(fp_line
			(start 0.7874 -0.4064)
			(end 0.7874 0.4064)
			(stroke
				(width 0.1524)
				(type default)
			)
			(layer "F.SilkS")
		)
		(fp_line
			(start -0.7874 -0.4064)
			(end 0.7874 -0.4064)
			(stroke
				(width 0.1524)
				(type default)
			)
			(layer "F.SilkS")
		)
		(fp_line
			(start 0.7874 0.4064)
			(end -0.7874 0.4064)
			(stroke
				(width 0.1524)
				(type default)
			)
			(layer "F.SilkS")
		)
		(fp_line
			(start -0.7874 0.4064)
			(end -0.7874 -0.4064)
			(stroke
				(width 0.1524)
				(type default)
			)
			(layer "F.SilkS")
		)
		(fp_line
			(start -0.12065 -0.305054)
			(end -0.12065 -0.2794)
			(stroke
				(width 0.1)
				(type default)
			)
			(layer "F.Fab")
		)
		(fp_line
			(start -0.67945 -0.305054)
			(end -0.12065 -0.305054)
			(stroke
				(width 0.1)
				(type default)
			)
			(layer "F.Fab")
		)
		(fp_line
			(start 0.67945 -0.3048)
			(end 0.67945 0.3048)
			(stroke
				(width 0.1)
				(type default)
			)
			(layer "F.Fab")
		)
		(fp_line
			(start 0.12065 -0.3048)
			(end 0.67945 -0.3048)
			(stroke
				(width 0.1)
				(type default)
			)
			(layer "F.Fab")
		)
		(fp_line
			(start 0.12065 -0.2794)
			(end 0.12065 -0.3048)
			(stroke
				(width 0.1)
				(type default)
			)
			(layer "F.Fab")
		)
		(fp_line
			(start -0.12065 -0.2794)
			(end 0.12065 -0.2794)
			(stroke
				(width 0.1)
				(type default)
			)
			(layer "F.Fab")
		)
		(fp_line
			(start 0.120396 0.2794)
			(end -0.12065 0.2794)
			(stroke
				(width 0.1)
				(type default)
			)
			(layer "F.Fab")
		)
		(fp_line
			(start -0.12065 0.2794)
			(end -0.12065 0.3048)
			(stroke
				(width 0.1)
				(type default)
			)
			(layer "F.Fab")
		)
		(fp_line
			(start 0.67945 0.3048)
			(end 0.120396 0.3048)
			(stroke
				(width 0.1)
				(type default)
			)
			(layer "F.Fab")
		)
		(fp_line
			(start 0.120396 0.3048)
			(end 0.120396 0.2794)
			(stroke
				(width 0.1)
				(type default)
			)
			(layer "F.Fab")
		)
		(fp_line
			(start -0.12065 0.3048)
			(end -0.67945 0.3048)
			(stroke
				(width 0.1)
				(type default)
			)
			(layer "F.Fab")
		)
		(fp_line
			(start -0.67945 0.3048)
			(end -0.67945 -0.305054)
			(stroke
				(width 0.1)
				(type default)
			)
			(layer "F.Fab")
		)
		(pad "1" smd circle
			(at -0.40005 0 90)
			(size 0 0)
			(layers "F.Cu" "F.Mask" "F.Paste")
			(net "P12V_SSD15_CO_MODE")
		)
		(pad "2" smd circle
			(at 0.40005 0 90)
			(size 0 0)
			(layers "F.Cu" "F.Mask" "F.Paste")
			(net "GND")
		)
	)
)
